(kicad_pcb
	(version 20260206)
	(generator "pcbnew")
	(generator_version "10.0")
	(general
		(thickness 1.6)
		(legacy_teardrops no)
	)
	(paper "A4")
	(title_block
		(title "pdpb — Lightning_PDPB_BRD.brd")
		(comment 1 "Lightning (Wiwynn / Facebook NVMe JBOF) / footprints 1014-1019 of 1140")
	)
	(layers
		(0 "F.Cu" signal "TOP")
		(4 "In1.Cu" signal "L2GND")
		(6 "In2.Cu" signal "L3")
		(8 "In3.Cu" signal "L4VCC")
		(10 "In4.Cu" signal "L5VCC")
		(12 "In5.Cu" signal "L6")
		(14 "In6.Cu" signal "L7GND")
		(2 "B.Cu" signal "BOTTOM")
		(9 "F.Adhes" user "F.Adhesive")
		(11 "B.Adhes" user "B.Adhesive")
		(13 "F.Paste" user "Package Geometry/Pastemask Top")
		(15 "B.Paste" user "Package Geometry/Pastemask Bottom")
		(5 "F.SilkS" user "Ref Des/Silkscreen Top")
		(7 "B.SilkS" user "Ref Des/Silkscreen Bottom")
		(1 "F.Mask" user "Board Geometry/Soldermask Top")
		(3 "B.Mask" user "Board Geometry/Soldermask Bottom")
		(17 "Dwgs.User" user "User.Drawings")
		(19 "Cmts.User" user "User.Comments")
		(21 "Eco1.User" user "User.Eco1")
		(23 "Eco2.User" user "User.Eco2")
		(25 "Edge.Cuts" user "Board Geometry/Outline")
		(27 "Margin" user)
		(31 "F.CrtYd" user "Package Geometry/Place Bound Top")
		(29 "B.CrtYd" user "Package Geometry/Place Bound Bottom")
		(35 "F.Fab" user "Ref Des/Assembly Top")
		(33 "B.Fab" user "Ref Des/Assembly Bottom")
	)
	(footprint ""
		(layer "F.Cu")
		(at 253.499874 -41.497504)
		(property "Reference" "H11"
			(at 0 0 0)
			(layer "F.SilkS")
			(hide yes)
			(effects
				(font
					(size 1.27 1.27)
				)
			)
		)
		(property "Value" "GEN276X162R197X296-6-F-A-GP"
			(at -6.7183 4.1402 0)
			(unlocked yes)
			(layer "F.Fab")
			(hide yes)
			(effects
				(font
					(size 1.016 1.016)
					(thickness 0.1524)
				)
			)
		)
		(property "Device Type" "GEN276X162R197X296-6-F-A"
			(at -6.7183 2.6162 0)
			(unlocked yes)
			(layer "F.Fab")
			(hide yes)
			(effects
				(font
					(size 1.016 1.016)
					(thickness 0.1524)
				)
			)
		)
		(duplicate_pad_numbers_are_jumpers no)
		(fp_poly
			(pts
				(arc
					(start 2.723642 4.777232)
					(mid -0.000169 6.508462)
					(end -2.723896 4.776978)
				)
				(arc
					(start -2.723896 4.776978)
					(mid 0.000173 -5.499012)
					(end 2.723642 4.777232)
				)
			)
			(stroke
				(width 0)
				(type default)
			)
			(fill no)
			(layer "B.CrtYd")
		)
		(fp_poly
			(pts
				(arc
					(start 2.723642 4.777232)
					(mid -0.000169 6.508462)
					(end -2.723896 4.776978)
				)
				(arc
					(start -2.723896 4.776978)
					(mid 0.000173 -5.499012)
					(end 2.723642 4.777232)
				)
			)
			(stroke
				(width 0)
				(type default)
			)
			(fill no)
			(layer "F.CrtYd")
		)
		(fp_poly
			(pts
				(arc
					(start 2.723642 4.777232)
					(mid -0.000169 6.508462)
					(end -2.723896 4.776978)
				)
				(arc
					(start -2.723896 4.776978)
					(mid 0.000173 -5.499012)
					(end 2.723642 4.777232)
				)
			)
			(stroke
				(width 0)
				(type default)
			)
			(fill no)
			(layer "B.Fab")
		)
		(fp_poly
			(pts
				(arc
					(start 2.723642 4.777232)
					(mid -0.000169 6.508462)
					(end -2.723896 4.776978)
				)
				(arc
					(start -2.723896 4.776978)
					(mid 0.000173 -5.499012)
					(end 2.723642 4.777232)
				)
			)
			(stroke
				(width 0)
				(type default)
			)
			(fill no)
			(layer "F.Fab")
		)
		(pad "" np_thru_hole circle
			(at 0 0)
			(size 0.254 0.254)
			(drill 0.0254)
			(layers "*.Cu" "*.Mask")
			(clearance 3.135376)
			(thermal_gap 3.135376)
		)
		(pad "1" thru_hole circle
			(at 2.549906 0)
			(size 0.8636 0.8636)
			(drill 0.508)
			(layers "*.Cu" "*.Mask")
			(remove_unused_layers no)
			(net "GND")
			(clearance 0.8255)
			(thermal_gap 0.8255)
		)
		(pad "2" thru_hole circle
			(at 2.210054 -1.27)
			(size 0.8636 0.8636)
			(drill 0.508)
			(layers "*.Cu" "*.Mask")
			(remove_unused_layers no)
			(net "GND")
			(clearance 0.8255)
			(thermal_gap 0.8255)
		)
		(pad "3" thru_hole circle
			(at 1.27 -2.210054)
			(size 0.8636 0.8636)
			(drill 0.508)
			(layers "*.Cu" "*.Mask")
			(remove_unused_layers no)
			(net "GND")
			(clearance 0.8255)
			(thermal_gap 0.8255)
		)
		(pad "4" thru_hole circle
			(at -1.279906 -2.210054)
			(size 0.8636 0.8636)
			(drill 0.508)
			(layers "*.Cu" "*.Mask")
			(remove_unused_layers no)
			(net "GND")
			(clearance 0.8255)
			(thermal_gap 0.8255)
		)
		(pad "5" thru_hole circle
			(at -2.210054 -1.27)
			(size 0.8636 0.8636)
			(drill 0.508)
			(layers "*.Cu" "*.Mask")
			(remove_unused_layers no)
			(net "GND")
			(clearance 0.8255)
			(thermal_gap 0.8255)
		)
		(pad "6" thru_hole circle
			(at -2.549906 0)
			(size 0.8636 0.8636)
			(drill 0.508)
			(layers "*.Cu" "*.Mask")
			(remove_unused_layers no)
			(net "GND")
			(clearance 0.8255)
			(thermal_gap 0.8255)
		)
		(zone
			(layers "F.Cu" "B.Cu" "In1.Cu" "In2.Cu" "In3.Cu" "In4.Cu" "In5.Cu" "In6.Cu")
			(hatch none 0.5)
			(connect_pads
				(clearance 0)
			)
			(min_thickness 0.25)
			(keepout
				(tracks allowed)
				(vias not_allowed)
				(pads allowed)
				(copperpour not_allowed)
				(footprints allowed)
			)
			(placement
				(enabled no)
				(sheetname "")
			)
			(fill
				(thermal_gap 0.5)
				(thermal_bridge_width 0.5)
				(island_removal_mode 0)
			)
			(polygon
				(pts
					(arc
						(start 257.817874 -41.500552)
						(mid 249.181874 -41.500552)
						(end 257.817874 -41.500552)
					)
				)
			)
		)
		(zone
			(layers "F.Cu" "B.Cu" "In1.Cu" "In2.Cu" "In3.Cu" "In4.Cu" "In5.Cu" "In6.Cu")
			(hatch none 0.5)
			(connect_pads
				(clearance 0)
			)
			(min_thickness 0.25)
			(keepout
				(tracks not_allowed)
				(vias allowed)
				(pads allowed)
				(copperpour not_allowed)
				(footprints allowed)
			)
			(placement
				(enabled no)
				(sheetname "")
			)
			(fill
				(thermal_gap 0.5)
				(thermal_bridge_width 0.5)
				(island_removal_mode 0)
			)
			(polygon
				(pts
					(arc
						(start 255.839214 -39.88816)
						(mid 253.499954 -34.989057)
						(end 251.16028 -39.88816)
					)
					(arc
						(start 251.16028 -39.88816)
						(mid 251.406247 -40.328526)
						(end 251.491496 -40.825674)
					)
					(arc
						(start 251.491496 -41.497504)
						(mid 253.499874 -43.505882)
						(end 255.507998 -41.497504)
					)
					(arc
						(start 255.507998 -40.825674)
						(mid 255.593233 -40.32852)
						(end 255.839214 -39.88816)
					)
				)
			)
		)
	)
	(footprint ""
		(layer "F.Cu")
		(at 98.552 -437.769 90)
		(property "Reference" "C8840"
			(at 0 0 90)
			(layer "F.SilkS")
			(hide yes)
			(effects
				(font
					(size 1.27 1.27)
				)
			)
		)
		(property "Value" "SCD1U16V2KX-3GP"
			(at 1.1811 -2.7051 90)
			(unlocked yes)
			(layer "F.Fab")
			(hide yes)
			(effects
				(font
					(size 1.016 1.016)
					(thickness 0.1524)
				)
			)
		)
		(property "Device Type" "C402H22"
			(at 1.1811 -4.2291 90)
			(unlocked yes)
			(layer "F.Fab")
			(hide yes)
			(effects
				(font
					(size 1.016 1.016)
					(thickness 0.1524)
				)
			)
		)
		(duplicate_pad_numbers_are_jumpers no)
		(fp_rect
			(start -0.4318 0.9525)
			(end 0.4318 -0.9525)
			(stroke
				(width 0)
				(type default)
			)
			(fill no)
			(layer "F.CrtYd")
		)
		(fp_rect
			(start -0.4318 0.9525)
			(end 0.4318 -0.9525)
			(stroke
				(width 0)
				(type default)
			)
			(fill no)
			(layer "F.Fab")
		)
		(pad "1" smd custom
			(at 0 -0.4445 90)
			(size 0.1524 0.1524)
			(layers "F.Cu" "F.Mask" "F.Paste")
			(net "VDD_IO_1")
			(options
				(clearance outline)
				(anchor circle)
			)
			(primitives
				(gr_poly
					(pts
						(arc
							(start 0.3048 -0.2032)
							(mid 0.275042 -0.275042)
							(end 0.2032 -0.3048)
						)
						(arc
							(start -0.2032 -0.3048)
							(mid -0.275042 -0.275042)
							(end -0.3048 -0.2032)
						)
						(arc
							(start -0.3048 0.2032)
							(mid -0.275042 0.275042)
							(end -0.2032 0.3048)
						)
						(arc
							(start 0.2032 0.3048)
							(mid 0.275042 0.275042)
							(end 0.3048 0.2032)
						)
					)
					(width 0)
					(fill yes)
				)
			)
		)
		(pad "2" smd custom
			(at 0 0.4445 90)
			(size 0.1524 0.1524)
			(layers "F.Cu" "F.Mask" "F.Paste")
			(net "GND")
			(options
				(clearance outline)
				(anchor circle)
			)
			(primitives
				(gr_poly
					(pts
						(arc
							(start 0.3048 -0.2032)
							(mid 0.275042 -0.275042)
							(end 0.2032 -0.3048)
						)
						(arc
							(start -0.2032 -0.3048)
							(mid -0.275042 -0.275042)
							(end -0.3048 -0.2032)
						)
						(arc
							(start -0.3048 0.2032)
							(mid -0.275042 0.275042)
							(end -0.2032 0.3048)
						)
						(arc
							(start 0.2032 0.3048)
							(mid 0.275042 0.275042)
							(end 0.3048 0.2032)
						)
					)
					(width 0)
					(fill yes)
				)
			)
		)
	)
	(footprint ""
		(layer "F.Cu")
		(at 59.817 -447.04 180)
		(property "Reference" "Q55"
			(at 0 0 180)
			(layer "F.SilkS")
			(hide yes)
			(effects
				(font
					(size 1.27 1.27)
				)
			)
		)
		(property "Value" "2N7002A-7-GP"
			(at 0.127 -8.9662 180)
			(unlocked yes)
			(layer "F.Fab")
			(hide yes)
			(effects
				(font
					(size 1.016 1.016)
					(thickness 0.1524)
				)
			)
		)
		(property "Device Type" "SOT23DGS2D4H48"
			(at 0.127 -10.4902 180)
			(unlocked yes)
			(layer "F.Fab")
			(hide yes)
			(effects
				(font
					(size 1.016 1.016)
					(thickness 0.1524)
				)
			)
		)
		(duplicate_pad_numbers_are_jumpers no)
		(fp_line
			(start 1.651 1.778)
			(end 1.651 -1.778)
			(stroke
				(width 0.1524)
				(type default)
			)
			(layer "F.SilkS")
		)
		(fp_line
			(start 1.651 -1.778)
			(end -1.651 -1.778)
			(stroke
				(width 0.1524)
				(type default)
			)
			(layer "F.SilkS")
		)
		(fp_line
			(start -1.651 1.778)
			(end 1.651 1.778)
			(stroke
				(width 0.1524)
				(type default)
			)
			(layer "F.SilkS")
		)
		(fp_line
			(start -1.651 -1.778)
			(end -1.651 1.778)
			(stroke
				(width 0.1524)
				(type default)
			)
			(layer "F.SilkS")
		)
		(fp_poly
			(pts
				(xy -1.778 1.8796) (xy -1.778 -1.8796) (xy 1.778 -1.8796) (xy 1.778 1.8796)
			)
			(stroke
				(width 0)
				(type default)
			)
			(fill no)
			(layer "F.CrtYd")
		)
		(fp_poly
			(pts
				(xy -1.778 1.8796) (xy -1.778 -1.8796) (xy 1.778 -1.8796) (xy 1.778 1.8796)
			)
			(stroke
				(width 0)
				(type default)
			)
			(fill no)
			(layer "F.Fab")
		)
		(pad "D" smd custom
			(at 0 -0.9525 180)
			(size 0.1905 0.1905)
			(layers "F.Cu" "F.Mask" "F.Paste")
			(net "ATTN_LED_DR5_MOS_N")
			(options
				(clearance outline)
				(anchor circle)
			)
			(primitives
				(gr_poly
					(pts
						(arc
							(start -0.1778 0.5715)
							(mid -0.321484 0.511984)
							(end -0.381 0.3683)
						)
						(arc
							(start -0.381 -0.3683)
							(mid -0.321484 -0.511984)
							(end -0.1778 -0.5715)
						)
						(arc
							(start 0.1778 -0.5715)
							(mid 0.321484 -0.511984)
							(end 0.381 -0.3683)
						)
						(arc
							(start 0.381 0.3683)
							(mid 0.321484 0.511984)
							(end 0.1778 0.5715)
						)
					)
					(width 0)
					(fill yes)
				)
			)
		)
		(pad "G" smd custom
			(at -0.98425 0.9525 180)
			(size 0.1905 0.1905)
			(layers "F.Cu" "F.Mask" "F.Paste")
			(net "SSD5_CLK0_OE_MOS_N")
			(options
				(clearance outline)
				(anchor circle)
			)
			(primitives
				(gr_poly
					(pts
						(arc
							(start -0.1778 0.5715)
							(mid -0.321484 0.511984)
							(end -0.381 0.3683)
						)
						(arc
							(start -0.381 -0.3683)
							(mid -0.321484 -0.511984)
							(end -0.1778 -0.5715)
						)
						(arc
							(start 0.1778 -0.5715)
							(mid 0.321484 -0.511984)
							(end 0.381 -0.3683)
						)
						(arc
							(start 0.381 0.3683)
							(mid 0.321484 0.511984)
							(end 0.1778 0.5715)
						)
					)
					(width 0)
					(fill yes)
				)
			)
		)
		(pad "S" smd custom
			(at 0.98425 0.9525 180)
			(size 0.1905 0.1905)
			(layers "F.Cu" "F.Mask" "F.Paste")
			(net "ATTN_LED_DR5_R")
			(options
				(clearance outline)
				(anchor circle)
			)
			(primitives
				(gr_poly
					(pts
						(arc
							(start -0.1778 0.5715)
							(mid -0.321484 0.511984)
							(end -0.381 0.3683)
						)
						(arc
							(start -0.381 -0.3683)
							(mid -0.321484 -0.511984)
							(end -0.1778 -0.5715)
						)
						(arc
							(start 0.1778 -0.5715)
							(mid 0.321484 -0.511984)
							(end 0.381 -0.3683)
						)
						(arc
							(start 0.381 0.3683)
							(mid 0.321484 0.511984)
							(end 0.1778 0.5715)
						)
					)
					(width 0)
					(fill yes)
				)
			)
		)
	)
	(footprint ""
		(layer "F.Cu")
		(at 24.7396 -498.5258 180)
		(property "Reference" "PC1206"
			(at 0 0 180)
			(layer "F.SilkS")
			(hide yes)
			(effects
				(font
					(size 1.27 1.27)
				)
			)
		)
		(property "Value" "SC22U25V6KX-GP-U"
			(at -2.860802 -5.279644 180)
			(unlocked yes)
			(layer "F.Fab")
			(hide yes)
			(effects
				(font
					(size 1.016 1.016)
					(thickness 0.1524)
				)
			)
		)
		(property "Device Type" "C1206-TO0D3H75"
			(at -2.860802 -6.803644 180)
			(unlocked yes)
			(layer "F.Fab")
			(hide yes)
			(effects
				(font
					(size 1.016 1.016)
					(thickness 0.1524)
				)
			)
		)
		(duplicate_pad_numbers_are_jumpers no)
		(fp_line
			(start 1.3081 2.3749)
			(end -1.3081 2.3749)
			(stroke
				(width 0.1524)
				(type default)
			)
			(layer "F.SilkS")
		)
		(fp_line
			(start 1.3081 -2.3749)
			(end 1.3081 2.3749)
			(stroke
				(width 0.1524)
				(type default)
			)
			(layer "F.SilkS")
		)
		(fp_line
			(start -1.3081 2.3749)
			(end -1.3081 -2.3749)
			(stroke
				(width 0.1524)
				(type default)
			)
			(layer "F.SilkS")
		)
		(fp_line
			(start -1.3081 -2.3749)
			(end 1.3081 -2.3749)
			(stroke
				(width 0.1524)
				(type default)
			)
			(layer "F.SilkS")
		)
		(fp_rect
			(start -0.8001 1.6002)
			(end 0.8001 -1.6002)
			(stroke
				(width 0)
				(type default)
			)
			(fill no)
			(layer "F.CrtYd")
		)
		(fp_poly
			(pts
				(xy -1.5621 2.4511) (xy -1.5621 1.6002) (xy 0.8001 1.6002) (xy 0.8001 -1.6002) (xy -0.8001 -1.6002)
				(xy -0.8001 1.5875) (xy -1.5621 1.5875) (xy -1.5621 -2.4511) (xy 1.5621 -2.4511) (xy 1.5621 2.4511)
			)
			(stroke
				(width 0)
				(type default)
			)
			(fill no)
			(layer "F.CrtYd")
		)
		(fp_rect
			(start -1.5621 2.4511)
			(end 1.5621 -2.4511)
			(stroke
				(width 0)
				(type default)
			)
			(fill no)
			(layer "F.Fab")
		)
		(pad "1" smd rect
			(at 0 -1.392936 180)
			(size 2.1082 1.4478)
			(layers "F.Cu" "F.Mask" "F.Paste")
			(net "P12V_SSD5")
		)
		(pad "2" smd rect
			(at 0 1.392936 180)
			(size 2.1082 1.4478)
			(layers "F.Cu" "F.Mask" "F.Paste")
			(net "GND")
		)
	)
	(footprint ""
		(layer "F.Cu")
		(at 33.02 -374.65)
		(property "Reference" "R339"
			(at 0 0 0)
			(layer "F.SilkS")
			(hide yes)
			(effects
				(font
					(size 1.27 1.27)
				)
			)
		)
		(property "Value" "4K7R2J-2-GP"
			(at 0.064008 -3.993896 0)
			(unlocked yes)
			(layer "F.Fab")
			(hide yes)
			(effects
				(font
					(size 1.016 1.016)
					(thickness 0.1524)
				)
			)
		)
		(property "Device Type" "R402H16"
			(at 0.064008 -5.517896 0)
			(unlocked yes)
			(layer "F.Fab")
			(hide yes)
			(effects
				(font
					(size 1.016 1.016)
					(thickness 0.1524)
				)
			)
		)
		(duplicate_pad_numbers_are_jumpers no)
		(fp_line
			(start -0.508 -0.9398)
			(end -0.508 0.9398)
			(stroke
				(width 0.1524)
				(type default)
			)
			(layer "F.SilkS")
		)
		(fp_line
			(start 0.508 -0.9398)
			(end -0.508 -0.9398)
			(stroke
				(width 0.1524)
				(type default)
			)
			(layer "F.SilkS")
		)
		(fp_rect
			(start -0.508 0.9398)
			(end 0.508 -0.9398)
			(stroke
				(width 0)
				(type default)
			)
			(fill no)
			(layer "F.CrtYd")
		)
		(fp_rect
			(start -0.508 0.9398)
			(end 0.508 -0.9398)
			(stroke
				(width 0)
				(type default)
			)
			(fill no)
			(layer "F.Fab")
		)
		(pad "1" smd custom
			(at 0 -0.4445)
			(size 0.1397 0.1397)
			(layers "F.Cu" "F.Mask" "F.Paste")
			(net "I2C_B_TMP4_A2")
			(options
				(clearance outline)
				(anchor circle)
			)
			(primitives
				(gr_poly
					(pts
						(arc
							(start -0.1778 -0.2794)
							(mid -0.249642 -0.249642)
							(end -0.2794 -0.1778)
						)
						(arc
							(start -0.2794 0.1778)
							(mid -0.249642 0.249642)
							(end -0.1778 0.2794)
						)
						(arc
							(start 0.1778 0.2794)
							(mid 0.249642 0.249642)
							(end 0.2794 0.1778)
						)
						(arc
							(start 0.2794 -0.1778)
							(mid 0.249642 -0.249642)
							(end 0.1778 -0.2794)
						)
					)
					(width 0)
					(fill yes)
				)
			)
		)
		(pad "2" smd custom
			(at 0 0.4445)
			(size 0.1397 0.1397)
			(layers "F.Cu" "F.Mask" "F.Paste")
			(net "GND")
			(options
				(clearance outline)
				(anchor circle)
			)
			(primitives
				(gr_poly
					(pts
						(arc
							(start -0.1778 -0.2794)
							(mid -0.249642 -0.249642)
							(end -0.2794 -0.1778)
						)
						(arc
							(start -0.2794 0.1778)
							(mid -0.249642 0.249642)
							(end -0.1778 0.2794)
						)
						(arc
							(start 0.1778 0.2794)
							(mid 0.249642 0.249642)
							(end 0.2794 0.1778)
						)
						(arc
							(start 0.2794 -0.1778)
							(mid 0.249642 -0.249642)
							(end 0.1778 -0.2794)
						)
					)
					(width 0)
					(fill yes)
				)
			)
		)
	)
	(footprint ""
		(layer "F.Cu")
		(at 32.2326 -421.513 180)
		(property "Reference" "SR1111"
			(at 0 0 180)
			(layer "F.SilkS")
			(hide yes)
			(effects
				(font
					(size 1.27 1.27)
				)
			)
		)
		(property "Value" "4K7R2F-GP"
			(at 0.064008 -3.993896 180)
			(unlocked yes)
			(layer "F.Fab")
			(hide yes)
			(effects
				(font
					(size 1.016 1.016)
					(thickness 0.1524)
				)
			)
		)
		(property "Device Type" "R402H16"
			(at 0.064008 -5.517896 180)
			(unlocked yes)
			(layer "F.Fab")
			(hide yes)
			(effects
				(font
					(size 1.016 1.016)
					(thickness 0.1524)
				)
			)
		)
		(duplicate_pad_numbers_are_jumpers no)
		(fp_line
			(start 0.508 -0.9398)
			(end -0.508 -0.9398)
			(stroke
				(width 0.1524)
				(type default)
			)
			(layer "F.SilkS")
		)
		(fp_line
			(start -0.508 -0.9398)
			(end -0.508 0.9398)
			(stroke
				(width 0.1524)
				(type default)
			)
			(layer "F.SilkS")
		)
		(fp_rect
			(start -0.508 0.9398)
			(end 0.508 -0.9398)
			(stroke
				(width 0)
				(type default)
			)
			(fill no)
			(layer "F.CrtYd")
		)
		(fp_rect
			(start -0.508 0.9398)
			(end 0.508 -0.9398)
			(stroke
				(width 0)
				(type default)
			)
			(fill no)
			(layer "F.Fab")
		)
		(pad "1" smd custom
			(at 0 -0.4445 180)
			(size 0.1397 0.1397)
			(layers "F.Cu" "F.Mask" "F.Paste")
			(net "P3V3")
			(options
				(clearance outline)
				(anchor circle)
			)
			(primitives
				(gr_poly
					(pts
						(arc
							(start -0.1778 -0.2794)
							(mid -0.249642 -0.249642)
							(end -0.2794 -0.1778)
						)
						(arc
							(start -0.2794 0.1778)
							(mid -0.249642 0.249642)
							(end -0.1778 0.2794)
						)
						(arc
							(start 0.1778 0.2794)
							(mid 0.249642 0.249642)
							(end 0.2794 0.1778)
						)
						(arc
							(start 0.2794 -0.1778)
							(mid 0.249642 -0.249642)
							(end 0.1778 -0.2794)
						)
					)
					(width 0)
					(fill yes)
				)
			)
		)
		(pad "2" smd custom
			(at 0 0.4445 180)
			(size 0.1397 0.1397)
			(layers "F.Cu" "F.Mask" "F.Paste")
			(net "DUALPORTEN#10")
			(options
				(clearance outline)
				(anchor circle)
			)
			(primitives
				(gr_poly
					(pts
						(arc
							(start -0.1778 -0.2794)
							(mid -0.249642 -0.249642)
							(end -0.2794 -0.1778)
						)
						(arc
							(start -0.2794 0.1778)
							(mid -0.249642 0.249642)
							(end -0.1778 0.2794)
						)
						(arc
							(start 0.1778 0.2794)
							(mid 0.249642 0.249642)
							(end 0.2794 0.1778)
						)
						(arc
							(start 0.2794 -0.1778)
							(mid 0.249642 -0.249642)
							(end 0.1778 -0.2794)
						)
					)
					(width 0)
					(fill yes)
				)
			)
		)
	)
)
